(kicad_pcb
	(version 20260206)
	(generator "pcbnew")
	(generator_version "10.0")
	(general
		(thickness 1.6)
		(legacy_teardrops no)
	)
	(paper "A4")
	(title_block
		(title "04192023_DAF0TMB3IC0_F0TG_MB_C_brd_V02_OCP.brd")
		(comment 1 "Grand Teton / footprints 1121-1127 of 8354")
	)
	(layers
		(0 "F.Cu" signal "TOP")
		(4 "In1.Cu" signal "GND")
		(6 "In2.Cu" signal "IN1")
		(8 "In3.Cu" signal "GND1")
		(10 "In4.Cu" signal "IN2")
		(12 "In5.Cu" signal "GND2")
		(14 "In6.Cu" signal "IN3")
		(16 "In7.Cu" signal "GND3")
		(18 "In8.Cu" signal "VCC")
		(20 "In9.Cu" signal "VCC1")
		(22 "In10.Cu" signal "GND4")
		(24 "In11.Cu" signal "IN4")
		(26 "In12.Cu" signal "GND5")
		(28 "In13.Cu" signal "IN5")
		(30 "In14.Cu" signal "GND6")
		(32 "In15.Cu" signal "IN6")
		(34 "In16.Cu" signal "GND7")
		(2 "B.Cu" signal "BOTTOM")
		(9 "F.Adhes" user "F.Adhesive")
		(11 "B.Adhes" user "B.Adhesive")
		(13 "F.Paste" user "Package Geometry/Pastemask Top")
		(15 "B.Paste" user "Package Geometry/Pastemask Bottom")
		(5 "F.SilkS" user "Ref Des/Silkscreen Top")
		(7 "B.SilkS" user "Ref Des/Silkscreen Bottom")
		(1 "F.Mask" user "Board Geometry/Soldermask Top")
		(3 "B.Mask" user "Board Geometry/Soldermask Bottom")
		(17 "Dwgs.User" user "User.Drawings")
		(19 "Cmts.User" user "User.Comments")
		(21 "Eco1.User" user "User.Eco1")
		(23 "Eco2.User" user "User.Eco2")
		(25 "Edge.Cuts" user "Board Geometry/Outline")
		(27 "Margin" user)
		(31 "F.CrtYd" user "Package Geometry/Place Bound Top")
		(29 "B.CrtYd" user "Package Geometry/Place Bound Bottom")
		(35 "F.Fab" user "Ref Des/Assembly Top")
		(33 "B.Fab" user "Ref Des/Assembly Bottom")
	)
	(footprint ""
		(layer "F.Cu")
		(at 435.102 -170.688 -90)
		(property "Reference" "R1300"
			(at 0 0 270)
			(layer "F.SilkS")
			(hide yes)
			(effects
				(font
					(size 1.27 1.27)
				)
			)
		)
		(property "Value" ""
			(at 0 0 270)
			(layer "F.Fab")
			(effects
				(font
					(size 1.27 1.27)
				)
			)
		)
		(duplicate_pad_numbers_are_jumpers no)
		(fp_line
			(start -0.7874 0.4064)
			(end -0.7874 -0.4064)
			(stroke
				(width 0.1524)
				(type default)
			)
			(layer "F.SilkS")
		)
		(fp_line
			(start 0.7874 0.4064)
			(end -0.7874 0.4064)
			(stroke
				(width 0.1524)
				(type default)
			)
			(layer "F.SilkS")
		)
		(fp_line
			(start -0.7874 -0.4064)
			(end 0.7874 -0.4064)
			(stroke
				(width 0.1524)
				(type default)
			)
			(layer "F.SilkS")
		)
		(fp_line
			(start 0.7874 -0.4064)
			(end 0.7874 0.4064)
			(stroke
				(width 0.1524)
				(type default)
			)
			(layer "F.SilkS")
		)
		(fp_line
			(start -0.67945 0.3048)
			(end -0.67945 -0.305054)
			(stroke
				(width 0.1)
				(type default)
			)
			(layer "F.Fab")
		)
		(fp_line
			(start -0.12065 0.3048)
			(end -0.67945 0.3048)
			(stroke
				(width 0.1)
				(type default)
			)
			(layer "F.Fab")
		)
		(fp_line
			(start 0.120396 0.3048)
			(end 0.120396 0.2794)
			(stroke
				(width 0.1)
				(type default)
			)
			(layer "F.Fab")
		)
		(fp_line
			(start 0.67945 0.3048)
			(end 0.120396 0.3048)
			(stroke
				(width 0.1)
				(type default)
			)
			(layer "F.Fab")
		)
		(fp_line
			(start -0.12065 0.2794)
			(end -0.12065 0.3048)
			(stroke
				(width 0.1)
				(type default)
			)
			(layer "F.Fab")
		)
		(fp_line
			(start 0.120396 0.2794)
			(end -0.12065 0.2794)
			(stroke
				(width 0.1)
				(type default)
			)
			(layer "F.Fab")
		)
		(fp_line
			(start -0.12065 -0.2794)
			(end 0.12065 -0.2794)
			(stroke
				(width 0.1)
				(type default)
			)
			(layer "F.Fab")
		)
		(fp_line
			(start 0.12065 -0.2794)
			(end 0.12065 -0.3048)
			(stroke
				(width 0.1)
				(type default)
			)
			(layer "F.Fab")
		)
		(fp_line
			(start 0.12065 -0.3048)
			(end 0.67945 -0.3048)
			(stroke
				(width 0.1)
				(type default)
			)
			(layer "F.Fab")
		)
		(fp_line
			(start 0.67945 -0.3048)
			(end 0.67945 0.3048)
			(stroke
				(width 0.1)
				(type default)
			)
			(layer "F.Fab")
		)
		(fp_line
			(start -0.67945 -0.305054)
			(end -0.12065 -0.305054)
			(stroke
				(width 0.1)
				(type default)
			)
			(layer "F.Fab")
		)
		(fp_line
			(start -0.12065 -0.305054)
			(end -0.12065 -0.2794)
			(stroke
				(width 0.1)
				(type default)
			)
			(layer "F.Fab")
		)
		(pad "1" smd rect
			(at -0.40005 0 90)
			(size 0.4572 0.508)
			(layers "F.Cu" "F.Mask" "F.Paste")
			(net "I3C_SPD_DDRGL_CPU0_SDA")
		)
		(pad "2" smd rect
			(at 0.40005 0 90)
			(size 0.4572 0.508)
			(layers "F.Cu" "F.Mask" "F.Paste")
			(net "I3C_SPD_DDRGL_CPU0_LVC1_SDA")
		)
	)
	(footprint ""
		(layer "F.Cu")
		(at 192.151 -137.632948 -90)
		(property "Reference" "R1567"
			(at 0 0 270)
			(layer "F.SilkS")
			(hide yes)
			(effects
				(font
					(size 1.27 1.27)
				)
			)
		)
		(property "Value" ""
			(at 0 0 270)
			(layer "F.Fab")
			(effects
				(font
					(size 1.27 1.27)
				)
			)
		)
		(duplicate_pad_numbers_are_jumpers no)
		(fp_line
			(start -0.7874 0.4064)
			(end -0.7874 -0.4064)
			(stroke
				(width 0.1524)
				(type default)
			)
			(layer "F.SilkS")
		)
		(fp_line
			(start 0.7874 0.4064)
			(end -0.7874 0.4064)
			(stroke
				(width 0.1524)
				(type default)
			)
			(layer "F.SilkS")
		)
		(fp_line
			(start -0.7874 -0.4064)
			(end 0.7874 -0.4064)
			(stroke
				(width 0.1524)
				(type default)
			)
			(layer "F.SilkS")
		)
		(fp_line
			(start 0.7874 -0.4064)
			(end 0.7874 0.4064)
			(stroke
				(width 0.1524)
				(type default)
			)
			(layer "F.SilkS")
		)
		(fp_line
			(start -0.67945 0.3048)
			(end -0.67945 -0.305054)
			(stroke
				(width 0.1)
				(type default)
			)
			(layer "F.Fab")
		)
		(fp_line
			(start -0.12065 0.3048)
			(end -0.67945 0.3048)
			(stroke
				(width 0.1)
				(type default)
			)
			(layer "F.Fab")
		)
		(fp_line
			(start 0.120396 0.3048)
			(end 0.120396 0.2794)
			(stroke
				(width 0.1)
				(type default)
			)
			(layer "F.Fab")
		)
		(fp_line
			(start 0.67945 0.3048)
			(end 0.120396 0.3048)
			(stroke
				(width 0.1)
				(type default)
			)
			(layer "F.Fab")
		)
		(fp_line
			(start -0.12065 0.2794)
			(end -0.12065 0.3048)
			(stroke
				(width 0.1)
				(type default)
			)
			(layer "F.Fab")
		)
		(fp_line
			(start 0.120396 0.2794)
			(end -0.12065 0.2794)
			(stroke
				(width 0.1)
				(type default)
			)
			(layer "F.Fab")
		)
		(fp_line
			(start -0.12065 -0.2794)
			(end 0.12065 -0.2794)
			(stroke
				(width 0.1)
				(type default)
			)
			(layer "F.Fab")
		)
		(fp_line
			(start 0.12065 -0.2794)
			(end 0.12065 -0.3048)
			(stroke
				(width 0.1)
				(type default)
			)
			(layer "F.Fab")
		)
		(fp_line
			(start 0.12065 -0.3048)
			(end 0.67945 -0.3048)
			(stroke
				(width 0.1)
				(type default)
			)
			(layer "F.Fab")
		)
		(fp_line
			(start 0.67945 -0.3048)
			(end 0.67945 0.3048)
			(stroke
				(width 0.1)
				(type default)
			)
			(layer "F.Fab")
		)
		(fp_line
			(start -0.67945 -0.305054)
			(end -0.12065 -0.305054)
			(stroke
				(width 0.1)
				(type default)
			)
			(layer "F.Fab")
		)
		(fp_line
			(start -0.12065 -0.305054)
			(end -0.12065 -0.2794)
			(stroke
				(width 0.1)
				(type default)
			)
			(layer "F.Fab")
		)
		(pad "1" smd circle
			(at -0.40005 0 270)
			(size 0 0)
			(layers "F.Cu" "F.Mask" "F.Paste")
			(net "PVDD18_S5_P0")
		)
		(pad "2" smd circle
			(at 0.40005 0 270)
			(size 0 0)
			(layers "F.Cu" "F.Mask" "F.Paste")
			(net "ROM_LS_EN")
		)
	)
	(footprint ""
		(layer "F.Cu")
		(at 332.071472 -395.066774 -90)
		(property "Reference" "R629"
			(at 0 0 270)
			(layer "F.SilkS")
			(hide yes)
			(effects
				(font
					(size 1.27 1.27)
				)
			)
		)
		(property "Value" ""
			(at 0 0 270)
			(layer "F.Fab")
			(effects
				(font
					(size 1.27 1.27)
				)
			)
		)
		(duplicate_pad_numbers_are_jumpers no)
		(fp_line
			(start -0.32512 0.175006)
			(end -0.32512 -0.175006)
			(stroke
				(width 0.1)
				(type default)
			)
			(layer "F.Fab")
		)
		(fp_line
			(start 0.32512 0.175006)
			(end -0.32512 0.175006)
			(stroke
				(width 0.1)
				(type default)
			)
			(layer "F.Fab")
		)
		(fp_line
			(start -0.32512 -0.175006)
			(end 0.32512 -0.175006)
			(stroke
				(width 0.1)
				(type default)
			)
			(layer "F.Fab")
		)
		(fp_line
			(start 0.32512 -0.175006)
			(end 0.32512 0.175006)
			(stroke
				(width 0.1)
				(type default)
			)
			(layer "F.Fab")
		)
		(pad "1" smd rect
			(at -0.2667 0 270)
			(size 0.3048 0.381)
			(layers "F.Cu" "F.Mask" "F.Paste")
			(net "CLK_100M_RETIMER_CPU0_P1_DN")
		)
		(pad "2" smd rect
			(at 0.2667 0 90)
			(size 0.3048 0.381)
			(layers "F.Cu" "F.Mask" "F.Paste")
			(net "GND")
		)
	)
	(footprint ""
		(layer "F.Cu")
		(at 152.849326 -39.02456 180)
		(property "Reference" "R3519"
			(at 0 0 180)
			(layer "F.SilkS")
			(hide yes)
			(effects
				(font
					(size 1.27 1.27)
				)
			)
		)
		(property "Value" ""
			(at 0 0 180)
			(layer "F.Fab")
			(effects
				(font
					(size 1.27 1.27)
				)
			)
		)
		(duplicate_pad_numbers_are_jumpers no)
		(fp_line
			(start 0.7874 0.4064)
			(end -0.7874 0.4064)
			(stroke
				(width 0.1524)
				(type default)
			)
			(layer "F.SilkS")
		)
		(fp_line
			(start 0.7874 -0.4064)
			(end 0.7874 0.4064)
			(stroke
				(width 0.1524)
				(type default)
			)
			(layer "F.SilkS")
		)
		(fp_line
			(start -0.7874 0.4064)
			(end -0.7874 -0.4064)
			(stroke
				(width 0.1524)
				(type default)
			)
			(layer "F.SilkS")
		)
		(fp_line
			(start -0.7874 -0.4064)
			(end 0.7874 -0.4064)
			(stroke
				(width 0.1524)
				(type default)
			)
			(layer "F.SilkS")
		)
		(fp_line
			(start 0.67945 0.3048)
			(end 0.120396 0.3048)
			(stroke
				(width 0.1)
				(type default)
			)
			(layer "F.Fab")
		)
		(fp_line
			(start 0.67945 -0.3048)
			(end 0.67945 0.3048)
			(stroke
				(width 0.1)
				(type default)
			)
			(layer "F.Fab")
		)
		(fp_line
			(start 0.12065 -0.2794)
			(end 0.12065 -0.3048)
			(stroke
				(width 0.1)
				(type default)
			)
			(layer "F.Fab")
		)
		(fp_line
			(start 0.12065 -0.3048)
			(end 0.67945 -0.3048)
			(stroke
				(width 0.1)
				(type default)
			)
			(layer "F.Fab")
		)
		(fp_line
			(start 0.120396 0.3048)
			(end 0.120396 0.2794)
			(stroke
				(width 0.1)
				(type default)
			)
			(layer "F.Fab")
		)
		(fp_line
			(start 0.120396 0.2794)
			(end -0.12065 0.2794)
			(stroke
				(width 0.1)
				(type default)
			)
			(layer "F.Fab")
		)
		(fp_line
			(start -0.12065 0.3048)
			(end -0.67945 0.3048)
			(stroke
				(width 0.1)
				(type default)
			)
			(layer "F.Fab")
		)
		(fp_line
			(start -0.12065 0.2794)
			(end -0.12065 0.3048)
			(stroke
				(width 0.1)
				(type default)
			)
			(layer "F.Fab")
		)
		(fp_line
			(start -0.12065 -0.2794)
			(end 0.12065 -0.2794)
			(stroke
				(width 0.1)
				(type default)
			)
			(layer "F.Fab")
		)
		(fp_line
			(start -0.12065 -0.305054)
			(end -0.12065 -0.2794)
			(stroke
				(width 0.1)
				(type default)
			)
			(layer "F.Fab")
		)
		(fp_line
			(start -0.67945 0.3048)
			(end -0.67945 -0.305054)
			(stroke
				(width 0.1)
				(type default)
			)
			(layer "F.Fab")
		)
		(fp_line
			(start -0.67945 -0.305054)
			(end -0.12065 -0.305054)
			(stroke
				(width 0.1)
				(type default)
			)
			(layer "F.Fab")
		)
		(pad "1" smd circle
			(at -0.40005 0 180)
			(size 0 0)
			(layers "F.Cu" "F.Mask" "F.Paste")
			(net "P3V3_OCP_V3_2")
		)
		(pad "2" smd circle
			(at 0.40005 0 180)
			(size 0 0)
			(layers "F.Cu" "F.Mask" "F.Paste")
			(net "SMB_OCP_V3_2_3V3AUX_BUF_SCL")
		)
	)
	(footprint ""
		(layer "F.Cu")
		(at 434.443632 -107.17403 90)
		(property "Reference" "PC2086"
			(at 0 0 90)
			(layer "F.SilkS")
			(hide yes)
			(effects
				(font
					(size 1.27 1.27)
				)
			)
		)
		(property "Value" ""
			(at 0 0 90)
			(layer "F.Fab")
			(effects
				(font
					(size 1.27 1.27)
				)
			)
		)
		(duplicate_pad_numbers_are_jumpers no)
		(fp_line
			(start 0.7874 -0.4064)
			(end 0.7874 0.4064)
			(stroke
				(width 0.1524)
				(type default)
			)
			(layer "F.SilkS")
		)
		(fp_line
			(start -0.7874 -0.4064)
			(end 0.7874 -0.4064)
			(stroke
				(width 0.1524)
				(type default)
			)
			(layer "F.SilkS")
		)
		(fp_line
			(start 0.7874 0.4064)
			(end -0.7874 0.4064)
			(stroke
				(width 0.1524)
				(type default)
			)
			(layer "F.SilkS")
		)
		(fp_line
			(start -0.7874 0.4064)
			(end -0.7874 -0.4064)
			(stroke
				(width 0.1524)
				(type default)
			)
			(layer "F.SilkS")
		)
		(fp_line
			(start -0.12065 -0.305054)
			(end -0.12065 -0.2794)
			(stroke
				(width 0.1)
				(type default)
			)
			(layer "F.Fab")
		)
		(fp_line
			(start -0.67945 -0.305054)
			(end -0.12065 -0.305054)
			(stroke
				(width 0.1)
				(type default)
			)
			(layer "F.Fab")
		)
		(fp_line
			(start 0.67945 -0.3048)
			(end 0.67945 0.3048)
			(stroke
				(width 0.1)
				(type default)
			)
			(layer "F.Fab")
		)
		(fp_line
			(start 0.12065 -0.3048)
			(end 0.67945 -0.3048)
			(stroke
				(width 0.1)
				(type default)
			)
			(layer "F.Fab")
		)
		(fp_line
			(start 0.12065 -0.2794)
			(end 0.12065 -0.3048)
			(stroke
				(width 0.1)
				(type default)
			)
			(layer "F.Fab")
		)
		(fp_line
			(start -0.12065 -0.2794)
			(end 0.12065 -0.2794)
			(stroke
				(width 0.1)
				(type default)
			)
			(layer "F.Fab")
		)
		(fp_line
			(start 0.120396 0.2794)
			(end -0.12065 0.2794)
			(stroke
				(width 0.1)
				(type default)
			)
			(layer "F.Fab")
		)
		(fp_line
			(start -0.12065 0.2794)
			(end -0.12065 0.3048)
			(stroke
				(width 0.1)
				(type default)
			)
			(layer "F.Fab")
		)
		(fp_line
			(start 0.67945 0.3048)
			(end 0.120396 0.3048)
			(stroke
				(width 0.1)
				(type default)
			)
			(layer "F.Fab")
		)
		(fp_line
			(start 0.120396 0.3048)
			(end 0.120396 0.2794)
			(stroke
				(width 0.1)
				(type default)
			)
			(layer "F.Fab")
		)
		(fp_line
			(start -0.12065 0.3048)
			(end -0.67945 0.3048)
			(stroke
				(width 0.1)
				(type default)
			)
			(layer "F.Fab")
		)
		(fp_line
			(start -0.67945 0.3048)
			(end -0.67945 -0.305054)
			(stroke
				(width 0.1)
				(type default)
			)
			(layer "F.Fab")
		)
		(pad "1" smd circle
			(at -0.40005 0 90)
			(size 0 0)
			(layers "F.Cu" "F.Mask" "F.Paste")
			(net "P3V3_OCP_VCC_1")
		)
		(pad "2" smd circle
			(at 0.40005 0 90)
			(size 0 0)
			(layers "F.Cu" "F.Mask" "F.Paste")
			(net "GND")
		)
	)
	(footprint ""
		(layer "F.Cu")
		(at 316.23 -366.395 90)
		(property "Reference" "PC76"
			(at 0 0 90)
			(layer "F.SilkS")
			(hide yes)
			(effects
				(font
					(size 1.27 1.27)
				)
			)
		)
		(property "Value" ""
			(at 0 0 90)
			(layer "F.Fab")
			(effects
				(font
					(size 1.27 1.27)
				)
			)
		)
		(duplicate_pad_numbers_are_jumpers no)
		(fp_line
			(start 0.7874 -0.4064)
			(end 0.7874 0.4064)
			(stroke
				(width 0.1524)
				(type default)
			)
			(layer "F.SilkS")
		)
		(fp_line
			(start -0.7874 -0.4064)
			(end 0.7874 -0.4064)
			(stroke
				(width 0.1524)
				(type default)
			)
			(layer "F.SilkS")
		)
		(fp_line
			(start 0.7874 0.4064)
			(end -0.7874 0.4064)
			(stroke
				(width 0.1524)
				(type default)
			)
			(layer "F.SilkS")
		)
		(fp_line
			(start -0.7874 0.4064)
			(end -0.7874 -0.4064)
			(stroke
				(width 0.1524)
				(type default)
			)
			(layer "F.SilkS")
		)
		(fp_line
			(start -0.12065 -0.305054)
			(end -0.12065 -0.2794)
			(stroke
				(width 0.1)
				(type default)
			)
			(layer "F.Fab")
		)
		(fp_line
			(start -0.67945 -0.305054)
			(end -0.12065 -0.305054)
			(stroke
				(width 0.1)
				(type default)
			)
			(layer "F.Fab")
		)
		(fp_line
			(start 0.67945 -0.3048)
			(end 0.67945 0.3048)
			(stroke
				(width 0.1)
				(type default)
			)
			(layer "F.Fab")
		)
		(fp_line
			(start 0.12065 -0.3048)
			(end 0.67945 -0.3048)
			(stroke
				(width 0.1)
				(type default)
			)
			(layer "F.Fab")
		)
		(fp_line
			(start 0.12065 -0.2794)
			(end 0.12065 -0.3048)
			(stroke
				(width 0.1)
				(type default)
			)
			(layer "F.Fab")
		)
		(fp_line
			(start -0.12065 -0.2794)
			(end 0.12065 -0.2794)
			(stroke
				(width 0.1)
				(type default)
			)
			(layer "F.Fab")
		)
		(fp_line
			(start 0.120396 0.2794)
			(end -0.12065 0.2794)
			(stroke
				(width 0.1)
				(type default)
			)
			(layer "F.Fab")
		)
		(fp_line
			(start -0.12065 0.2794)
			(end -0.12065 0.3048)
			(stroke
				(width 0.1)
				(type default)
			)
			(layer "F.Fab")
		)
		(fp_line
			(start 0.67945 0.3048)
			(end 0.120396 0.3048)
			(stroke
				(width 0.1)
				(type default)
			)
			(layer "F.Fab")
		)
		(fp_line
			(start 0.120396 0.3048)
			(end 0.120396 0.2794)
			(stroke
				(width 0.1)
				(type default)
			)
			(layer "F.Fab")
		)
		(fp_line
			(start -0.12065 0.3048)
			(end -0.67945 0.3048)
			(stroke
				(width 0.1)
				(type default)
			)
			(layer "F.Fab")
		)
		(fp_line
			(start -0.67945 0.3048)
			(end -0.67945 -0.305054)
			(stroke
				(width 0.1)
				(type default)
			)
			(layer "F.Fab")
		)
		(pad "1" smd circle
			(at -0.40005 0 90)
			(size 0 0)
			(layers "F.Cu" "F.Mask" "F.Paste")
			(net "PVDDCR_CPU1_P0_VCCS")
		)
		(pad "2" smd circle
			(at 0.40005 0 90)
			(size 0 0)
			(layers "F.Cu" "F.Mask" "F.Paste")
			(net "GND")
		)
	)
	(footprint ""
		(layer "F.Cu")
		(at 76.070714 -339.850476 90)
		(property "Reference" "PC373_2"
			(at 0 0 90)
			(layer "F.SilkS")
			(hide yes)
			(effects
				(font
					(size 1.27 1.27)
				)
			)
		)
		(property "Value" ""
			(at 0 0 90)
			(layer "F.Fab")
			(effects
				(font
					(size 1.27 1.27)
				)
			)
		)
		(duplicate_pad_numbers_are_jumpers no)
		(fp_line
			(start 0.7874 -0.4064)
			(end 0.7874 0.4064)
			(stroke
				(width 0.1524)
				(type default)
			)
			(layer "F.SilkS")
		)
		(fp_line
			(start -0.7874 -0.4064)
			(end 0.7874 -0.4064)
			(stroke
				(width 0.1524)
				(type default)
			)
			(layer "F.SilkS")
		)
		(fp_line
			(start 0.7874 0.4064)
			(end -0.7874 0.4064)
			(stroke
				(width 0.1524)
				(type default)
			)
			(layer "F.SilkS")
		)
		(fp_line
			(start -0.7874 0.4064)
			(end -0.7874 -0.4064)
			(stroke
				(width 0.1524)
				(type default)
			)
			(layer "F.SilkS")
		)
		(fp_line
			(start -0.12065 -0.305054)
			(end -0.12065 -0.2794)
			(stroke
				(width 0.1)
				(type default)
			)
			(layer "F.Fab")
		)
		(fp_line
			(start -0.67945 -0.305054)
			(end -0.12065 -0.305054)
			(stroke
				(width 0.1)
				(type default)
			)
			(layer "F.Fab")
		)
		(fp_line
			(start 0.67945 -0.3048)
			(end 0.67945 0.3048)
			(stroke
				(width 0.1)
				(type default)
			)
			(layer "F.Fab")
		)
		(fp_line
			(start 0.12065 -0.3048)
			(end 0.67945 -0.3048)
			(stroke
				(width 0.1)
				(type default)
			)
			(layer "F.Fab")
		)
		(fp_line
			(start 0.12065 -0.2794)
			(end 0.12065 -0.3048)
			(stroke
				(width 0.1)
				(type default)
			)
			(layer "F.Fab")
		)
		(fp_line
			(start -0.12065 -0.2794)
			(end 0.12065 -0.2794)
			(stroke
				(width 0.1)
				(type default)
			)
			(layer "F.Fab")
		)
		(fp_line
			(start 0.120396 0.2794)
			(end -0.12065 0.2794)
			(stroke
				(width 0.1)
				(type default)
			)
			(layer "F.Fab")
		)
		(fp_line
			(start -0.12065 0.2794)
			(end -0.12065 0.3048)
			(stroke
				(width 0.1)
				(type default)
			)
			(layer "F.Fab")
		)
		(fp_line
			(start 0.67945 0.3048)
			(end 0.120396 0.3048)
			(stroke
				(width 0.1)
				(type default)
			)
			(layer "F.Fab")
		)
		(fp_line
			(start 0.120396 0.3048)
			(end 0.120396 0.2794)
			(stroke
				(width 0.1)
				(type default)
			)
			(layer "F.Fab")
		)
		(fp_line
			(start -0.12065 0.3048)
			(end -0.67945 0.3048)
			(stroke
				(width 0.1)
				(type default)
			)
			(layer "F.Fab")
		)
		(fp_line
			(start -0.67945 0.3048)
			(end -0.67945 -0.305054)
			(stroke
				(width 0.1)
				(type default)
			)
			(layer "F.Fab")
		)
		(pad "1" smd circle
			(at -0.40005 0 90)
			(size 0 0)
			(layers "F.Cu" "F.Mask" "F.Paste")
			(net "PVDDCR_CPU1_P1_VCCS")
		)
		(pad "2" smd circle
			(at 0.40005 0 90)
			(size 0 0)
			(layers "F.Cu" "F.Mask" "F.Paste")
			(net "GND")
		)
	)
)
